# S9S_MB_2U (Grand Teton) — schematic netlist excerpt (pin names and nets, part order shuffled) for the footprints in the layout excerpt that follows; sources: Cadence DE-HDL packaged netlist, KiCad conversion of 03242023_DA0F0TMBIJ0_F0T_Motherboard_J_brd_V01_OCP.brd

U103  INA183A1IDBVR  EMPTY  pkg SOT23-5_0-95_2-9X1-6XD  page 251
  GND0  = GND
  GND1  = GND
  \out\  = PVCCD_HV_CPU1_NVDIMM_ISENSE
  \in-\  = P12V_AUX_CPU1_DIMM_ISEN_N
  \in+\  = P12V_AUX_CPU1_DIMM_ISEN_P

D85  Q_LED  IC  pkg SMLF  page 254 : A = LED_PWRGD_PVNN_MAIN_CPU1 ; C = LED_PWRGD_PVNN_MAIN_CPU1_D
H74  HOLE  EMPTY  pkg TH  page 311 : \1\ = NC

(kicad_pcb
	(version 20260206)
	(generator "pcbnew")
	(generator_version "10.0")
	(general
		(thickness 1.6)
		(legacy_teardrops no)
	)
	(paper "A4")
	(title_block
		(title "03242023_DA0F0TMBIJ0_F0T_Motherboard_J_brd_V01_OCP.brd")
		(comment 1 "Grand Teton / footprints 2763-2765 of 6105")
	)
	(layers
		(0 "F.Cu" signal "TOP")
		(4 "In1.Cu" signal "GND")
		(6 "In2.Cu" signal "IN1")
		(8 "In3.Cu" signal "GND1")
		(10 "In4.Cu" signal "IN2")
		(12 "In5.Cu" signal "GND2")
		(14 "In6.Cu" signal "IN3")
		(16 "In7.Cu" signal "GND3")
		(18 "In8.Cu" signal "VCC")
		(20 "In9.Cu" signal "VCC1")
		(22 "In10.Cu" signal "GND4")
		(24 "In11.Cu" signal "IN4")
		(26 "In12.Cu" signal "GND5")
		(28 "In13.Cu" signal "IN5")
		(30 "In14.Cu" signal "GND6")
		(32 "In15.Cu" signal "IN6")
		(34 "In16.Cu" signal "GND7")
		(2 "B.Cu" signal "BOTTOM")
		(9 "F.Adhes" user "F.Adhesive")
		(11 "B.Adhes" user "B.Adhesive")
		(13 "F.Paste" user "Package Geometry/Pastemask Top")
		(15 "B.Paste" user "Package Geometry/Pastemask Bottom")
		(5 "F.SilkS" user "Ref Des/Silkscreen Top")
		(7 "B.SilkS" user "Ref Des/Silkscreen Bottom")
		(1 "F.Mask" user "Board Geometry/Soldermask Top")
		(3 "B.Mask" user "Board Geometry/Soldermask Bottom")
		(17 "Dwgs.User" user "User.Drawings")
		(19 "Cmts.User" user "User.Comments")
		(21 "Eco1.User" user "User.Eco1")
		(23 "Eco2.User" user "User.Eco2")
		(25 "Edge.Cuts" user "Board Geometry/Outline")
		(27 "Margin" user)
		(31 "F.CrtYd" user "Package Geometry/Place Bound Top")
		(29 "B.CrtYd" user "Package Geometry/Place Bound Bottom")
		(35 "F.Fab" user "Ref Des/Assembly Top")
		(33 "B.Fab" user "Ref Des/Assembly Bottom")
	)
	(footprint ""
		(layer "F.Cu")
		(at 16.35506 -335.871312)
		(property "Reference" "U103"
			(at -5.4864 -3.969258 0)
			(unlocked yes)
			(layer "F.SilkS")
			(effects
				(font
					(size 0.7874 0.5842)
					(thickness 0.1524)
				)
				(justify left)
			)
		)
		(property "Value" ""
			(at 0 0 0)
			(layer "F.Fab")
			(effects
				(font
					(size 1.27 1.27)
				)
			)
		)
		(duplicate_pad_numbers_are_jumpers no)
		(fp_line
			(start -1.99263 -1.525016)
			(end -1.99263 1.525016)
			(stroke
				(width 0.1524)
				(type default)
			)
			(layer "F.SilkS")
		)
		(fp_line
			(start -1.99263 1.525016)
			(end 1.99263 1.525016)
			(stroke
				(width 0.1524)
				(type default)
			)
			(layer "F.SilkS")
		)
		(fp_line
			(start 1.99263 -1.525016)
			(end -1.99263 -1.525016)
			(stroke
				(width 0.1524)
				(type default)
			)
			(layer "F.SilkS")
		)
		(fp_line
			(start 1.99263 1.525016)
			(end 1.99263 -1.525016)
			(stroke
				(width 0.1524)
				(type default)
			)
			(layer "F.SilkS")
		)
		(fp_poly
			(pts
				(xy -4.286504 -1.43764) (xy -3.270504 -0.92964) (xy -4.286504 -0.42164)
			)
			(stroke
				(width 0)
				(type default)
			)
			(fill yes)
			(layer "F.SilkS")
		)
		(fp_line
			(start -0.87503 -1.525016)
			(end -0.87503 1.525016)
			(stroke
				(width 0.1)
				(type default)
			)
			(layer "F.Fab")
		)
		(fp_line
			(start -0.87503 1.525016)
			(end 0.87503 1.525016)
			(stroke
				(width 0.1)
				(type default)
			)
			(layer "F.Fab")
		)
		(fp_line
			(start 0.87503 -1.525016)
			(end -0.87503 -1.525016)
			(stroke
				(width 0.1)
				(type default)
			)
			(layer "F.Fab")
		)
		(fp_line
			(start 0.87503 1.525016)
			(end 0.87503 -1.525016)
			(stroke
				(width 0.1)
				(type default)
			)
			(layer "F.Fab")
		)
		(fp_poly
			(pts
				(xy -3.2004 -1.45796) (xy -3.2004 -0.44196) (xy -2.1844 -0.94996)
			)
			(stroke
				(width 0)
				(type default)
			)
			(fill yes)
			(layer "F.Fab")
		)
		(pad "1" smd circle
			(at -1.299972 -0.94996 270)
			(size 0 0)
			(layers "F.Cu" "F.Mask" "F.Paste")
			(net "GND")
		)
		(pad "2" smd circle
			(at -1.299972 0 270)
			(size 0 0)
			(layers "F.Cu" "F.Mask" "F.Paste")
			(net "GND")
		)
		(pad "3" smd circle
			(at -1.299972 0.94996 270)
			(size 0 0)
			(layers "F.Cu" "F.Mask" "F.Paste")
			(net "PVCCD_HV_CPU1_NVDIMM_ISENSE")
		)
		(pad "4" smd circle
			(at 1.299972 0.94996 270)
			(size 0 0)
			(layers "F.Cu" "F.Mask" "F.Paste")
			(net "P12V_AUX_CPU1_DIMM_ISEN_N")
		)
		(pad "5" smd circle
			(at 1.299972 -0.94996 270)
			(size 0 0)
			(layers "F.Cu" "F.Mask" "F.Paste")
			(net "P12V_AUX_CPU1_DIMM_ISEN_P")
		)
	)
	(footprint ""
		(layer "F.Cu")
		(at 93.582998 -47.049944 90)
		(property "Reference" "H74"
			(at -4.312666 -0.46101 0)
			(unlocked yes)
			(layer "F.SilkS")
			(effects
				(font
					(size 0.7874 0.5842)
					(thickness 0.1524)
				)
			)
		)
		(property "Value" ""
			(at 0 0 90)
			(layer "F.Fab")
			(effects
				(font
					(size 1.27 1.27)
				)
			)
		)
		(duplicate_pad_numbers_are_jumpers no)
		(pad "" np_thru_hole circle
			(at 0 0 90)
			(size 0 0)
			(drill oval 3.2004 4.8006)
			(layers "*.Cu" "*.Mask")
			(clearance -1.2192)
			(thermal_gap 0.381)
			(padstack
				(mode front_inner_back)
				(layer "Inner"
					(shape oval)
					(size 3.2004 4.8006)
					(clearance 0.381)
				)
				(layer "B.Cu"
					(shape circle)
					(size 0 0)
					(clearance -1.2192)
				)
			)
		)
		(zone
			(layers "F.Cu" "B.Cu" "In1.Cu" "In2.Cu" "In3.Cu" "In4.Cu" "In5.Cu" "In6.Cu"
				"In7.Cu" "In8.Cu" "In9.Cu" "In10.Cu" "In11.Cu" "In12.Cu" "In13.Cu" "In14.Cu"
				"In15.Cu" "In16.Cu"
			)
			(hatch none 0.5)
			(connect_pads
				(clearance 0)
			)
			(min_thickness 0.25)
			(keepout
				(tracks not_allowed)
				(vias allowed)
				(pads allowed)
				(copperpour not_allowed)
				(footprints allowed)
			)
			(placement
				(enabled no)
				(sheetname "")
			)
			(fill
				(thermal_gap 0.5)
				(thermal_bridge_width 0.5)
				(island_removal_mode 0)
			)
			(polygon
				(pts
					(arc
						(start 94.383098 -49.158144)
						(mid 96.491298 -47.049944)
						(end 94.383098 -44.941744)
					)
					(arc
						(start 92.782898 -44.941744)
						(mid 90.674698 -47.049944)
						(end 92.782898 -49.158144)
					)
				)
			)
		)
		(zone
			(layers "F.Cu" "B.Cu" "In1.Cu" "In2.Cu" "In3.Cu" "In4.Cu" "In5.Cu" "In6.Cu"
				"In7.Cu" "In8.Cu" "In9.Cu" "In10.Cu" "In11.Cu" "In12.Cu" "In13.Cu" "In14.Cu"
				"In15.Cu" "In16.Cu"
			)
			(hatch none 0.5)
			(connect_pads
				(clearance 0)
			)
			(min_thickness 0.25)
			(keepout
				(tracks not_allowed)
				(vias allowed)
				(pads allowed)
				(copperpour not_allowed)
				(footprints allowed)
			)
			(placement
				(enabled no)
				(sheetname "")
			)
			(fill
				(thermal_gap 0.5)
				(thermal_bridge_width 0.5)
				(island_removal_mode 0)
			)
			(polygon
				(pts
					(arc
						(start 94.383098 -50.050192)
						(mid 97.383346 -47.049944)
						(end 94.383098 -44.049696)
					)
					(arc
						(start 92.782898 -44.049696)
						(mid 89.78265 -47.049944)
						(end 92.782898 -50.050192)
					)
				)
			)
		)
	)
	(footprint ""
		(layer "F.Cu")
		(at 103.384096 -70.78599)
		(property "Reference" "D85"
			(at -51.698906 50.178462 90)
			(unlocked yes)
			(layer "F.SilkS")
			(effects
				(font
					(size 0.635 0.4064)
					(thickness 0.1524)
				)
				(justify left)
			)
		)
		(property "Value" ""
			(at 0 0 0)
			(layer "F.Fab")
			(effects
				(font
					(size 1.27 1.27)
				)
			)
		)
		(duplicate_pad_numbers_are_jumpers no)
		(fp_line
			(start -0.90678 0.4826)
			(end -0.90678 -0.4699)
			(stroke
				(width 0.1524)
				(type default)
			)
			(layer "F.SilkS")
		)
		(fp_line
			(start -0.89408 -0.4826)
			(end 0.90678 -0.4826)
			(stroke
				(width 0.1524)
				(type default)
			)
			(layer "F.SilkS")
		)
		(fp_line
			(start -0.79248 -0.4826)
			(end 1.03378 -0.4826)
			(stroke
				(width 0.1524)
				(type default)
			)
			(layer "F.SilkS")
		)
		(fp_line
			(start -0.64008 -0.4826)
			(end 1.16078 -0.4826)
			(stroke
				(width 0.1524)
				(type default)
			)
			(layer "F.SilkS")
		)
		(fp_line
			(start 0.90678 -0.4826)
			(end 0.90678 0.4826)
			(stroke
				(width 0.1524)
				(type default)
			)
			(layer "F.SilkS")
		)
		(fp_line
			(start 0.90678 0.4826)
			(end -0.90678 0.4826)
			(stroke
				(width 0.1524)
				(type default)
			)
			(layer "F.SilkS")
		)
		(fp_line
			(start 1.03378 -0.4826)
			(end 1.03378 0.4826)
			(stroke
				(width 0.1524)
				(type default)
			)
			(layer "F.SilkS")
		)
		(fp_line
			(start 1.03378 0.4826)
			(end -0.79248 0.4826)
			(stroke
				(width 0.1524)
				(type default)
			)
			(layer "F.SilkS")
		)
		(fp_line
			(start 1.16078 -0.4826)
			(end 1.16078 0.4826)
			(stroke
				(width 0.1524)
				(type default)
			)
			(layer "F.SilkS")
		)
		(fp_line
			(start 1.16078 0.4826)
			(end -0.64008 0.4826)
			(stroke
				(width 0.1524)
				(type default)
			)
			(layer "F.SilkS")
		)
		(fp_line
			(start -0.499872 -0.249936)
			(end 0.499872 -0.249936)
			(stroke
				(width 0.1)
				(type default)
			)
			(layer "F.Fab")
		)
		(fp_line
			(start -0.499872 0.249936)
			(end -0.499872 -0.249936)
			(stroke
				(width 0.1)
				(type default)
			)
			(layer "F.Fab")
		)
		(fp_line
			(start 0.499872 -0.249936)
			(end 0.499872 0.249936)
			(stroke
				(width 0.1)
				(type default)
			)
			(layer "F.Fab")
		)
		(fp_line
			(start 0.499872 0.249936)
			(end -0.499872 0.249936)
			(stroke
				(width 0.1)
				(type default)
			)
			(layer "F.Fab")
		)
		(pad "A" smd rect
			(at -0.47498 0)
			(size 0.6096 0.7112)
			(layers "F.Cu" "F.Mask" "F.Paste")
			(net "LED_PWRGD_PVNN_MAIN_CPU1")
		)
		(pad "C" smd rect
			(at 0.47498 0)
			(size 0.6096 0.7112)
			(layers "F.Cu" "F.Mask" "F.Paste")
			(net "LED_PWRGD_PVNN_MAIN_CPU1_D")
		)
	)
)
